# T6G (Grand Teton) — schematic netlist excerpt (pin names and nets, part order shuffled) for the footprints in the layout excerpt that follows; sources: Cadence DE-HDL packaged netlist, KiCad conversion of 04192023_DAF0TMB3IC0_F0TG_MB_C_brd_V02_OCP.brd

PR3982  Q_RES  120K 1% CHIP  pkg 0402LF  page 264 : A = AGND_HSC ; B = HSC_MODE_3
R1003  Q_RES  0 5% EMPTY  pkg 0402LF  page 290 : A = P1V8_CPU0_RT1_1A_1D ; B = P1V8_CPU0_RT1_1A
C6576  Q_CAP_DIFFBUS  DIFF BUS_0.22UF 6.3V 20% X6S  pkg C0201  page 297 : \1\ = P5E_CPU0_P2_TX_BUF_C_DN<5> ; \2\ = P5E_CPU0_P2_TX_BUF_DN<5>

(kicad_pcb
	(version 20260206)
	(generator "pcbnew")
	(generator_version "10.0")
	(general
		(thickness 1.6)
		(legacy_teardrops no)
	)
	(paper "A4")
	(title_block
		(title "04192023_DAF0TMB3IC0_F0TG_MB_C_brd_V02_OCP.brd")
		(comment 1 "Grand Teton / footprints 2736-2738 of 8354")
	)
	(layers
		(0 "F.Cu" signal "TOP")
		(4 "In1.Cu" signal "GND")
		(6 "In2.Cu" signal "IN1")
		(8 "In3.Cu" signal "GND1")
		(10 "In4.Cu" signal "IN2")
		(12 "In5.Cu" signal "GND2")
		(14 "In6.Cu" signal "IN3")
		(16 "In7.Cu" signal "GND3")
		(18 "In8.Cu" signal "VCC")
		(20 "In9.Cu" signal "VCC1")
		(22 "In10.Cu" signal "GND4")
		(24 "In11.Cu" signal "IN4")
		(26 "In12.Cu" signal "GND5")
		(28 "In13.Cu" signal "IN5")
		(30 "In14.Cu" signal "GND6")
		(32 "In15.Cu" signal "IN6")
		(34 "In16.Cu" signal "GND7")
		(2 "B.Cu" signal "BOTTOM")
		(9 "F.Adhes" user "F.Adhesive")
		(11 "B.Adhes" user "B.Adhesive")
		(13 "F.Paste" user "Package Geometry/Pastemask Top")
		(15 "B.Paste" user "Package Geometry/Pastemask Bottom")
		(5 "F.SilkS" user "Ref Des/Silkscreen Top")
		(7 "B.SilkS" user "Ref Des/Silkscreen Bottom")
		(1 "F.Mask" user "Board Geometry/Soldermask Top")
		(3 "B.Mask" user "Board Geometry/Soldermask Bottom")
		(17 "Dwgs.User" user "User.Drawings")
		(19 "Cmts.User" user "User.Comments")
		(21 "Eco1.User" user "User.Eco1")
		(23 "Eco2.User" user "User.Eco2")
		(25 "Edge.Cuts" user "Board Geometry/Outline")
		(27 "Margin" user)
		(31 "F.CrtYd" user "Package Geometry/Place Bound Top")
		(29 "B.CrtYd" user "Package Geometry/Place Bound Bottom")
		(35 "F.Fab" user "Ref Des/Assembly Top")
		(33 "B.Fab" user "Ref Des/Assembly Bottom")
	)
	(footprint ""
		(layer "F.Cu")
		(at 358.389936 -392.48588 180)
		(property "Reference" "R1003"
			(at 0 0 180)
			(layer "F.SilkS")
			(hide yes)
			(effects
				(font
					(size 1.27 1.27)
				)
			)
		)
		(property "Value" ""
			(at 0 0 180)
			(layer "F.Fab")
			(effects
				(font
					(size 1.27 1.27)
				)
			)
		)
		(duplicate_pad_numbers_are_jumpers no)
		(fp_line
			(start 0.7874 0.4064)
			(end -0.7874 0.4064)
			(stroke
				(width 0.1524)
				(type default)
			)
			(layer "F.SilkS")
		)
		(fp_line
			(start 0.7874 -0.4064)
			(end 0.7874 0.4064)
			(stroke
				(width 0.1524)
				(type default)
			)
			(layer "F.SilkS")
		)
		(fp_line
			(start -0.7874 0.4064)
			(end -0.7874 -0.4064)
			(stroke
				(width 0.1524)
				(type default)
			)
			(layer "F.SilkS")
		)
		(fp_line
			(start -0.7874 -0.4064)
			(end 0.7874 -0.4064)
			(stroke
				(width 0.1524)
				(type default)
			)
			(layer "F.SilkS")
		)
		(fp_line
			(start 0.67945 0.3048)
			(end 0.120396 0.3048)
			(stroke
				(width 0.1)
				(type default)
			)
			(layer "F.Fab")
		)
		(fp_line
			(start 0.67945 -0.3048)
			(end 0.67945 0.3048)
			(stroke
				(width 0.1)
				(type default)
			)
			(layer "F.Fab")
		)
		(fp_line
			(start 0.12065 -0.2794)
			(end 0.12065 -0.3048)
			(stroke
				(width 0.1)
				(type default)
			)
			(layer "F.Fab")
		)
		(fp_line
			(start 0.12065 -0.3048)
			(end 0.67945 -0.3048)
			(stroke
				(width 0.1)
				(type default)
			)
			(layer "F.Fab")
		)
		(fp_line
			(start 0.120396 0.3048)
			(end 0.120396 0.2794)
			(stroke
				(width 0.1)
				(type default)
			)
			(layer "F.Fab")
		)
		(fp_line
			(start 0.120396 0.2794)
			(end -0.12065 0.2794)
			(stroke
				(width 0.1)
				(type default)
			)
			(layer "F.Fab")
		)
		(fp_line
			(start -0.12065 0.3048)
			(end -0.67945 0.3048)
			(stroke
				(width 0.1)
				(type default)
			)
			(layer "F.Fab")
		)
		(fp_line
			(start -0.12065 0.2794)
			(end -0.12065 0.3048)
			(stroke
				(width 0.1)
				(type default)
			)
			(layer "F.Fab")
		)
		(fp_line
			(start -0.12065 -0.2794)
			(end 0.12065 -0.2794)
			(stroke
				(width 0.1)
				(type default)
			)
			(layer "F.Fab")
		)
		(fp_line
			(start -0.12065 -0.305054)
			(end -0.12065 -0.2794)
			(stroke
				(width 0.1)
				(type default)
			)
			(layer "F.Fab")
		)
		(fp_line
			(start -0.67945 0.3048)
			(end -0.67945 -0.305054)
			(stroke
				(width 0.1)
				(type default)
			)
			(layer "F.Fab")
		)
		(fp_line
			(start -0.67945 -0.305054)
			(end -0.12065 -0.305054)
			(stroke
				(width 0.1)
				(type default)
			)
			(layer "F.Fab")
		)
		(pad "1" smd rect
			(at -0.40005 0)
			(size 0.4572 0.508)
			(layers "F.Cu" "F.Mask" "F.Paste")
			(net "P1V8_CPU0_RT1_1A_1D")
		)
		(pad "2" smd rect
			(at 0.40005 0)
			(size 0.4572 0.508)
			(layers "F.Cu" "F.Mask" "F.Paste")
			(net "P1V8_CPU0_RT1_1A")
		)
	)
	(footprint ""
		(layer "F.Cu")
		(at 386.184902 -416.899344 -90)
		(property "Reference" "C6576"
			(at 0 0 270)
			(layer "F.SilkS")
			(hide yes)
			(effects
				(font
					(size 1.27 1.27)
				)
			)
		)
		(property "Value" ""
			(at 0 0 270)
			(layer "F.Fab")
			(effects
				(font
					(size 1.27 1.27)
				)
			)
		)
		(duplicate_pad_numbers_are_jumpers no)
		(fp_line
			(start -0.299974 0.150114)
			(end -0.299974 -0.150114)
			(stroke
				(width 0.1)
				(type default)
			)
			(layer "F.Fab")
		)
		(fp_line
			(start 0.299974 0.150114)
			(end -0.299974 0.150114)
			(stroke
				(width 0.1)
				(type default)
			)
			(layer "F.Fab")
		)
		(fp_line
			(start -0.299974 -0.150114)
			(end 0.299974 -0.150114)
			(stroke
				(width 0.1)
				(type default)
			)
			(layer "F.Fab")
		)
		(fp_line
			(start 0.299974 -0.150114)
			(end 0.299974 0.150114)
			(stroke
				(width 0.1)
				(type default)
			)
			(layer "F.Fab")
		)
		(pad "1" smd rect
			(at -0.2667 0 270)
			(size 0.3048 0.381)
			(layers "F.Cu" "F.Mask" "F.Paste")
			(net "P5E_CPU0_P2_TX_BUF_C_DN<5>")
		)
		(pad "2" smd rect
			(at 0.2667 0 270)
			(size 0.3048 0.381)
			(layers "F.Cu" "F.Mask" "F.Paste")
			(net "P5E_CPU0_P2_TX_BUF_DN<5>")
		)
	)
	(footprint ""
		(layer "F.Cu")
		(at 226.0981 -407.068782 180)
		(property "Reference" "PR3982"
			(at 0 0 180)
			(layer "F.SilkS")
			(hide yes)
			(effects
				(font
					(size 1.27 1.27)
				)
			)
		)
		(property "Value" ""
			(at 0 0 180)
			(layer "F.Fab")
			(effects
				(font
					(size 1.27 1.27)
				)
			)
		)
		(duplicate_pad_numbers_are_jumpers no)
		(fp_line
			(start 0.7874 0.4064)
			(end -0.7874 0.4064)
			(stroke
				(width 0.1524)
				(type default)
			)
			(layer "F.SilkS")
		)
		(fp_line
			(start 0.7874 -0.4064)
			(end 0.7874 0.4064)
			(stroke
				(width 0.1524)
				(type default)
			)
			(layer "F.SilkS")
		)
		(fp_line
			(start -0.7874 0.4064)
			(end -0.7874 -0.4064)
			(stroke
				(width 0.1524)
				(type default)
			)
			(layer "F.SilkS")
		)
		(fp_line
			(start -0.7874 -0.4064)
			(end 0.7874 -0.4064)
			(stroke
				(width 0.1524)
				(type default)
			)
			(layer "F.SilkS")
		)
		(fp_line
			(start 0.67945 0.3048)
			(end 0.120396 0.3048)
			(stroke
				(width 0.1)
				(type default)
			)
			(layer "F.Fab")
		)
		(fp_line
			(start 0.67945 -0.3048)
			(end 0.67945 0.3048)
			(stroke
				(width 0.1)
				(type default)
			)
			(layer "F.Fab")
		)
		(fp_line
			(start 0.12065 -0.2794)
			(end 0.12065 -0.3048)
			(stroke
				(width 0.1)
				(type default)
			)
			(layer "F.Fab")
		)
		(fp_line
			(start 0.12065 -0.3048)
			(end 0.67945 -0.3048)
			(stroke
				(width 0.1)
				(type default)
			)
			(layer "F.Fab")
		)
		(fp_line
			(start 0.120396 0.3048)
			(end 0.120396 0.2794)
			(stroke
				(width 0.1)
				(type default)
			)
			(layer "F.Fab")
		)
		(fp_line
			(start 0.120396 0.2794)
			(end -0.12065 0.2794)
			(stroke
				(width 0.1)
				(type default)
			)
			(layer "F.Fab")
		)
		(fp_line
			(start -0.12065 0.3048)
			(end -0.67945 0.3048)
			(stroke
				(width 0.1)
				(type default)
			)
			(layer "F.Fab")
		)
		(fp_line
			(start -0.12065 0.2794)
			(end -0.12065 0.3048)
			(stroke
				(width 0.1)
				(type default)
			)
			(layer "F.Fab")
		)
		(fp_line
			(start -0.12065 -0.2794)
			(end 0.12065 -0.2794)
			(stroke
				(width 0.1)
				(type default)
			)
			(layer "F.Fab")
		)
		(fp_line
			(start -0.12065 -0.305054)
			(end -0.12065 -0.2794)
			(stroke
				(width 0.1)
				(type default)
			)
			(layer "F.Fab")
		)
		(fp_line
			(start -0.67945 0.3048)
			(end -0.67945 -0.305054)
			(stroke
				(width 0.1)
				(type default)
			)
			(layer "F.Fab")
		)
		(fp_line
			(start -0.67945 -0.305054)
			(end -0.12065 -0.305054)
			(stroke
				(width 0.1)
				(type default)
			)
			(layer "F.Fab")
		)
		(pad "1" smd circle
			(at -0.40005 0 180)
			(size 0 0)
			(layers "F.Cu" "F.Mask" "F.Paste")
			(net "AGND_HSC")
		)
		(pad "2" smd circle
			(at 0.40005 0 180)
			(size 0 0)
			(layers "F.Cu" "F.Mask" "F.Paste")
			(net "HSC_MODE_3")
		)
	)
)
